(kicad_pcb
	(version 20241229)
	(generator "pcbnew")
	(generator_version "9.0")
	(general
		(thickness 1.6642)
		(legacy_teardrops no)
	)
	(paper "A3")
	(title_block
		(title "PolarFire SoM")
		(date "2025-07-22")
		(rev "1.1.4")
		(company "Antmicro Ltd")
		(comment 1 "www.antmicro.com")
		(comment 9 "footprints 49-52 of 470")
	)
	(layers
		(0 "F.Cu" mixed)
		(4 "In1.Cu" power)
		(6 "In2.Cu" signal)
		(8 "In3.Cu" power)
		(10 "In4.Cu" signal)
		(12 "In5.Cu" power)
		(14 "In6.Cu" power)
		(16 "In7.Cu" signal)
		(18 "In8.Cu" power)
		(20 "In9.Cu" signal)
		(22 "In10.Cu" power)
		(24 "In11.Cu" signal)
		(26 "In12.Cu" signal)
		(2 "B.Cu" mixed)
		(9 "F.Adhes" user "F.Adhesive")
		(11 "B.Adhes" user "B.Adhesive")
		(13 "F.Paste" user)
		(15 "B.Paste" user)
		(5 "F.SilkS" user "F.Silkscreen")
		(7 "B.SilkS" user "B.Silkscreen")
		(1 "F.Mask" user)
		(3 "B.Mask" user)
		(17 "Dwgs.User" user "User.Drawings")
		(19 "Cmts.User" user "User.Comments")
		(21 "Eco1.User" user "User.Eco1")
		(23 "Eco2.User" user "User.Eco2")
		(25 "Edge.Cuts" user)
		(27 "Margin" user)
		(31 "F.CrtYd" user "F.Courtyard")
		(29 "B.CrtYd" user "B.Courtyard")
		(35 "F.Fab" user)
		(33 "B.Fab" user)
	)
	(footprint "antmicro-footprints:C_0402_1005Metric"
		(layer "F.Cu")
		(at 186.684904 147.897281 -90)
		(descr "Capacitor SMD 0402")
		(tags "capacitor SMD 0402")
		(property "Reference" "C110"
			(at 4.06272 -6.315096 180)
			(layer "F.SilkS")
			(effects
				(font
					(size 0.7 0.7)
					(thickness 0.15)
				)
				(justify right bottom)
			)
		)
		(property "Value" "C_22u_0402"
			(at -1.022927 2.155213 90)
			(layer "F.Fab")
			(hide yes)
			(effects
				(font
					(size 0.7 0.7)
					(thickness 0.15)
				)
				(justify right bottom)
			)
		)
		(property "Datasheet" "https://www.murata.com/products/productdetail?partno=GRM158R60J226ME01%23"
			(at 0 0 270)
			(layer "F.Fab")
			(hide yes)
			(effects
				(font
					(size 1.27 1.27)
					(thickness 0.15)
				)
			)
		)
		(property "Description" "SMD Multilayer Ceramic Capacitor, 22 uF, 4 V, 0402 [1005 Metric], X6S"
			(at 0 0 270)
			(layer "F.Fab")
			(hide yes)
			(effects
				(font
					(size 1.27 1.27)
					(thickness 0.15)
				)
			)
		)
		(property "Author" "Antmicro"
			(at 38.787623 334.582185 0)
			(layer "F.Fab")
			(hide yes)
			(effects
				(font
					(size 1 1)
					(thickness 0.15)
				)
			)
		)
		(property "Dielectric" ""
			(at 38.787623 334.582185 0)
			(layer "F.Fab")
			(hide yes)
			(effects
				(font
					(size 1 1)
					(thickness 0.15)
				)
			)
		)
		(property "License" "Apache-2.0"
			(at 38.787623 334.582185 0)
			(layer "F.Fab")
			(hide yes)
			(effects
				(font
					(size 1 1)
					(thickness 0.15)
				)
			)
		)
		(property "MPN" "GRM158R60J226ME01D"
			(at 38.787623 334.582185 0)
			(layer "F.Fab")
			(hide yes)
			(effects
				(font
					(size 1 1)
					(thickness 0.15)
				)
			)
		)
		(property "Manufacturer" "Murata"
			(at 38.787623 334.582185 0)
			(layer "F.Fab")
			(hide yes)
			(effects
				(font
					(size 1 1)
					(thickness 0.15)
				)
			)
		)
		(property "Public" ""
			(at 38.787623 334.582185 0)
			(layer "F.Fab")
			(hide yes)
			(effects
				(font
					(size 1 1)
					(thickness 0.15)
				)
			)
		)
		(property "Val" "22u"
			(at 38.787623 334.582185 0)
			(layer "F.Fab")
			(hide yes)
			(effects
				(font
					(size 1 1)
					(thickness 0.15)
				)
			)
		)
		(property "Voltage" ""
			(at 38.787623 334.582185 0)
			(layer "F.Fab")
			(hide yes)
			(effects
				(font
					(size 1 1)
					(thickness 0.15)
				)
			)
		)
		(sheetname "/Supply/")
		(sheetfile "supply.kicad_sch")
		(attr smd)
		(fp_rect
			(start -0.925 -0.47)
			(end 0.925 0.47)
			(stroke
				(width 0.05)
				(type default)
			)
			(fill no)
			(layer "F.CrtYd")
		)
		(fp_line
			(start -0.494 0.248)
			(end -0.494 -0.25)
			(stroke
				(width 0.15)
				(type solid)
			)
			(layer "F.Fab")
		)
		(fp_line
			(start 0.504 0.248)
			(end -0.494 0.248)
			(stroke
				(width 0.15)
				(type solid)
			)
			(layer "F.Fab")
		)
		(fp_line
			(start -0.494 -0.25)
			(end 0.504 -0.25)
			(stroke
				(width 0.15)
				(type solid)
			)
			(layer "F.Fab")
		)
		(fp_line
			(start 0.504 -0.25)
			(end 0.504 0.248)
			(stroke
				(width 0.15)
				(type solid)
			)
			(layer "F.Fab")
		)
		(fp_text user "${REFERENCE}"
			(at -0.939 4.599 270)
			(layer "F.Fab")
			(effects
				(font
					(size 0.7 0.7)
					(thickness 0.15)
				)
				(justify left bottom)
			)
		)
		(fp_text user "Author: Antmicro"
			(at -0.939 3.399 270)
			(layer "F.Fab")
			(effects
				(font
					(size 0.7 0.7)
					(thickness 0.15)
				)
				(justify left bottom)
			)
		)
		(fp_text user "License: Apache-2.0"
			(at -0.939 5.799 270)
			(layer "F.Fab")
			(effects
				(font
					(size 0.7 0.7)
					(thickness 0.15)
				)
				(justify left bottom)
			)
		)
		(pad "1" smd roundrect
			(at -0.48 0 270)
			(size 0.59 0.64)
			(layers "F.Cu" "F.Mask" "F.Paste")
			(roundrect_rratio 0.25)
			(net 417 "GND")
			(pintype "passive")
		)
		(pad "2" smd roundrect
			(at 0.48 0 270)
			(size 0.59 0.64)
			(layers "F.Cu" "F.Mask" "F.Paste")
			(roundrect_rratio 0.25)
			(net 522 "/Supply/1V05_REG")
			(pintype "passive")
		)
	)
	(footprint "antmicro-footprints:XSON-8_1x1.95mm_P0.5mm"
		(layer "F.Cu")
		(at 225.45 123.45 90)
		(property "Reference" "U24"
			(at -1.6 2.15 90)
			(layer "F.SilkS")
			(effects
				(font
					(size 0.7 0.7)
					(thickness 0.15)
				)
				(justify left bottom)
			)
		)
		(property "Value" "NTS0102_XSON"
			(at 0 2.2 90)
			(layer "F.Fab")
			(hide yes)
			(effects
				(font
					(size 0.7 0.7)
					(thickness 0.15)
				)
				(justify left bottom)
			)
		)
		(property "Datasheet" "http://www.farnell.com/datasheets/1760723.pdf"
			(at 0 0 90)
			(layer "F.Fab")
			(hide yes)
			(effects
				(font
					(size 1.27 1.27)
					(thickness 0.15)
				)
			)
		)
		(property "Description" "Transceiver, 1.65 V to 3.6 V, XSON-8"
			(at 0 0 90)
			(layer "F.Fab")
			(hide yes)
			(effects
				(font
					(size 1.27 1.27)
					(thickness 0.15)
				)
			)
		)
		(property "Author" "Antmicro"
			(at 348.9 -102 0)
			(layer "F.Fab")
			(hide yes)
			(effects
				(font
					(size 1 1)
					(thickness 0.15)
				)
			)
		)
		(property "License" "Apache-2.0"
			(at 348.9 -102 0)
			(layer "F.Fab")
			(hide yes)
			(effects
				(font
					(size 1 1)
					(thickness 0.15)
				)
			)
		)
		(property "MPN" "NTS0102GT"
			(at 348.9 -102 0)
			(layer "F.Fab")
			(hide yes)
			(effects
				(font
					(size 1 1)
					(thickness 0.15)
				)
			)
		)
		(property "Manufacturer" "NXP"
			(at 348.9 -102 0)
			(layer "F.Fab")
			(hide yes)
			(effects
				(font
					(size 1 1)
					(thickness 0.15)
				)
			)
		)
		(sheetname "/FPGA GPIO/")
		(sheetfile "fpga-gpio.kicad_sch")
		(attr smd)
		(fp_line
			(start -0.5 -1.1)
			(end 0.5 -1.1)
			(stroke
				(width 0.15)
				(type solid)
			)
			(layer "F.SilkS")
		)
		(fp_line
			(start 0.5 1.1)
			(end -0.5 1.1)
			(stroke
				(width 0.15)
				(type solid)
			)
			(layer "F.SilkS")
		)
		(fp_circle
			(center -0.75 -1.1)
			(end -0.701 -1.1)
			(stroke
				(width 0.15)
				(type solid)
			)
			(fill no)
			(layer "F.SilkS")
		)
		(fp_rect
			(start -0.8 -1.2)
			(end 0.8 1.2)
			(stroke
				(width 0.05)
				(type solid)
			)
			(fill no)
			(layer "F.CrtYd")
		)
		(fp_line
			(start 0.5305 -1.001)
			(end 0.5305 1)
			(stroke
				(width 0.15)
				(type solid)
			)
			(layer "F.Fab")
		)
		(fp_line
			(start -0.5305 -1.001)
			(end 0.5305 -1.001)
			(stroke
				(width 0.15)
				(type solid)
			)
			(layer "F.Fab")
		)
		(fp_line
			(start 0.5305 1)
			(end -0.5305 1)
			(stroke
				(width 0.15)
				(type solid)
			)
			(layer "F.Fab")
		)
		(fp_line
			(start -0.5305 1)
			(end -0.5305 -1.001)
			(stroke
				(width 0.15)
				(type solid)
			)
			(layer "F.Fab")
		)
		(fp_text user "${REFERENCE}"
			(at -0.527 5.905 90)
			(layer "F.Fab")
			(effects
				(font
					(size 0.7 0.7)
					(thickness 0.15)
				)
				(justify left bottom)
			)
		)
		(fp_text user "Author: Antmicro"
			(at -0.527 7.105 90)
			(layer "F.Fab")
			(effects
				(font
					(size 0.7 0.7)
					(thickness 0.15)
				)
				(justify left bottom)
			)
		)
		(fp_text user "License: Apache-2.0"
			(at -0.527 8.306 90)
			(layer "F.Fab")
			(effects
				(font
					(size 0.7 0.7)
					(thickness 0.15)
				)
				(justify left bottom)
			)
		)
		(pad "1" smd roundrect
			(at -0.45 -0.75 270)
			(size 0.6 0.3)
			(layers "F.Cu" "F.Mask" "F.Paste")
			(roundrect_rratio 0.25)
			(net 253 "ETH_RESET_n")
			(pinfunction "B_{2}")
			(pintype "bidirectional")
		)
		(pad "2" smd roundrect
			(at -0.45 -0.25 270)
			(size 0.6 0.25)
			(layers "F.Cu" "F.Mask" "F.Paste")
			(roundrect_rratio 0.25)
			(net 417 "GND")
			(pinfunction "GND")
			(pintype "power_in")
		)
		(pad "3" smd roundrect
			(at -0.45 0.25 270)
			(size 0.6 0.25)
			(layers "F.Cu" "F.Mask" "F.Paste")
			(roundrect_rratio 0.25)
			(net 649 "VDD")
			(pinfunction "VCC_{A}")
			(pintype "power_in")
		)
		(pad "4" smd roundrect
			(at -0.45 0.75 270)
			(size 0.6 0.3)
			(layers "F.Cu" "F.Mask" "F.Paste")
			(roundrect_rratio 0.25)
			(net 566 "/FPGA GPIO/PF_ETH_RESET_n")
			(pinfunction "A_{2}")
			(pintype "bidirectional")
		)
		(pad "5" smd roundrect
			(at 0.45 0.75 270)
			(size 0.6 0.3)
			(layers "F.Cu" "F.Mask" "F.Paste")
			(roundrect_rratio 0.25)
			(net 565 "/FPGA GPIO/PF_ETH_PWDN_n")
			(pinfunction "A_{1}")
			(pintype "bidirectional")
		)
		(pad "6" smd roundrect
			(at 0.45 0.25 270)
			(size 0.6 0.25)
			(layers "F.Cu" "F.Mask" "F.Paste")
			(roundrect_rratio 0.25)
			(net 649 "VDD")
			(pinfunction "OE")
			(pintype "input")
		)
		(pad "7" smd roundrect
			(at 0.45 -0.25 270)
			(size 0.6 0.25)
			(layers "F.Cu" "F.Mask" "F.Paste")
			(roundrect_rratio 0.25)
			(net 50 "+3V3")
			(pinfunction "VCC_{B}")
			(pintype "power_in")
		)
		(pad "8" smd roundrect
			(at 0.45 -0.75 270)
			(size 0.6 0.3)
			(layers "F.Cu" "F.Mask" "F.Paste")
			(roundrect_rratio 0.25)
			(net 217 "ETH_PWDN_n")
			(pinfunction "B_{1}")
			(pintype "bidirectional")
		)
	)
	(footprint "antmicro-footprints:R_0402_1005Metric"
		(layer "F.Cu")
		(at 227.16 141.26 90)
		(descr "Resistor SMD 0402")
		(tags "resistor SMD 0402")
		(property "Reference" "R152"
			(at -1.122484 -0.772697 90)
			(layer "F.SilkS")
			(hide yes)
			(effects
				(font
					(size 0.7 0.7)
					(thickness 0.15)
				)
				(justify left bottom)
			)
		)
		(property "Value" "R_0R_0402"
			(at -1.011843 1.772047 90)
			(layer "F.Fab")
			(hide yes)
			(effects
				(font
					(size 0.7 0.7)
					(thickness 0.15)
				)
				(justify left bottom)
			)
		)
		(property "Datasheet" "https://industrial.panasonic.com/cdbs/www-data/pdf/RDA0000/AOA0000C301.pdf"
			(at 0 0 90)
			(layer "F.Fab")
			(hide yes)
			(effects
				(font
					(size 1.27 1.27)
					(thickness 0.15)
				)
			)
		)
		(property "Description" "SMD Chip Resistor, Jumper, 0 ohm, 100 mW, 0402 [1005 Metric], Thick Film, General Purpose"
			(at 0 0 90)
			(layer "F.Fab")
			(hide yes)
			(effects
				(font
					(size 1.27 1.27)
					(thickness 0.15)
				)
			)
		)
		(property "Author" "Antmicro"
			(at 368.42 -85.9 0)
			(layer "F.Fab")
			(hide yes)
			(effects
				(font
					(size 1 1)
					(thickness 0.15)
				)
			)
		)
		(property "Current" "1A"
			(at 368.42 -85.9 0)
			(layer "F.Fab")
			(hide yes)
			(effects
				(font
					(size 1 1)
					(thickness 0.15)
				)
			)
		)
		(property "License" "Apache-2.0"
			(at 368.42 -85.9 0)
			(layer "F.Fab")
			(hide yes)
			(effects
				(font
					(size 1 1)
					(thickness 0.15)
				)
			)
		)
		(property "MPN" "ERJ2GE0R00X"
			(at 368.42 -85.9 0)
			(layer "F.Fab")
			(hide yes)
			(effects
				(font
					(size 1 1)
					(thickness 0.15)
				)
			)
		)
		(property "Manufacturer" "Panasonic"
			(at 368.42 -85.9 0)
			(layer "F.Fab")
			(hide yes)
			(effects
				(font
					(size 1 1)
					(thickness 0.15)
				)
			)
		)
		(property "Public" ""
			(at 368.42 -85.9 0)
			(layer "F.Fab")
			(hide yes)
			(effects
				(font
					(size 1 1)
					(thickness 0.15)
				)
			)
		)
		(property "Tolerance" "~"
			(at 368.42 -85.9 0)
			(layer "F.Fab")
			(hide yes)
			(effects
				(font
					(size 1 1)
					(thickness 0.15)
				)
			)
		)
		(property "Val" "0R"
			(at 368.42 -85.9 0)
			(layer "F.Fab")
			(hide yes)
			(effects
				(font
					(size 1 1)
					(thickness 0.15)
				)
			)
		)
		(sheetname "/WiFi_Bluetooth/")
		(sheetfile "wifi_bt.kicad_sch")
		(attr smd)
		(fp_rect
			(start -0.925 -0.47)
			(end 0.925 0.47)
			(stroke
				(width 0.05)
				(type default)
			)
			(fill no)
			(layer "F.CrtYd")
		)
		(fp_rect
			(start -0.5 -0.25)
			(end 0.5 0.25)
			(stroke
				(width 0.15)
				(type solid)
			)
			(fill no)
			(layer "F.Fab")
		)
		(fp_text user "License: Apache-2.0"
			(at -0.95 5.169 90)
			(layer "F.Fab")
			(effects
				(font
					(size 0.7 0.7)
					(thickness 0.15)
				)
				(justify left bottom)
			)
		)
		(fp_text user "Author: Antmicro"
			(at -0.95 4.169 90)
			(layer "F.Fab")
			(effects
				(font
					(size 0.7 0.7)
					(thickness 0.15)
				)
				(justify left bottom)
			)
		)
		(fp_text user "${REFERENCE}"
			(at -0.95 3.168 90)
			(layer "F.Fab")
			(effects
				(font
					(size 0.7 0.7)
					(thickness 0.15)
				)
				(justify left bottom)
			)
		)
		(pad "1" smd roundrect
			(at -0.48 0 90)
			(size 0.59 0.64)
			(layers "F.Cu" "F.Mask" "F.Paste")
			(roundrect_rratio 0.25)
			(net 232 "Net-(U26A-WL_ANT)")
			(pintype "passive")
		)
		(pad "2" smd roundrect
			(at 0.48 0 90)
			(size 0.59 0.64)
			(layers "F.Cu" "F.Mask" "F.Paste")
			(roundrect_rratio 0.25)
			(net 178 "Net-(J3-Pad1)")
			(pintype "passive")
		)
	)
	(footprint "antmicro-footprints:Oscillator_SMD_ECS_1612MV_1.6x1.2x0.6mm"
		(layer "F.Cu")
		(at 198.3 144.13 90)
		(property "Reference" "Y5"
			(at 0.8 -0.77 180)
			(layer "F.SilkS")
			(effects
				(font
					(size 0.7 0.7)
					(thickness 0.15)
				)
				(justify left bottom)
			)
		)
		(property "Value" "Oscillator_50MHz_ECS_1612MV"
			(at 1.75 1.25 90)
			(layer "F.Fab")
			(hide yes)
			(effects
				(font
					(size 0.7 0.7)
					(thickness 0.15)
				)
				(justify left bottom)
			)
		)
		(property "Datasheet" "https://ecsxtal.com/store/pdf/ECS-1612MV.pdf"
			(at 0 0 90)
			(layer "F.Fab")
			(hide yes)
			(effects
				(font
					(size 1.27 1.27)
					(thickness 0.15)
				)
			)
		)
		(property "Description" "50 MHz XO (Standard) CMOS Oscillator 1.6V ~ 3.63V Standby 4-SMD, No Lead"
			(at 0 0 90)
			(layer "F.Fab")
			(hide yes)
			(effects
				(font
					(size 1.27 1.27)
					(thickness 0.15)
				)
			)
		)
		(property "Author" "Antmicro"
			(at 342.43 -54.17 0)
			(layer "F.Fab")
			(hide yes)
			(effects
				(font
					(size 1 1)
					(thickness 0.15)
				)
			)
		)
		(property "License" "Apache-2.0"
			(at 342.43 -54.17 0)
			(layer "F.Fab")
			(hide yes)
			(effects
				(font
					(size 1 1)
					(thickness 0.15)
				)
			)
		)
		(property "MPN" "ECS-1612MV-500-CN-TR"
			(at 342.43 -54.17 0)
			(layer "F.Fab")
			(hide yes)
			(effects
				(font
					(size 1 1)
					(thickness 0.15)
				)
			)
		)
		(property "Manufacturer" "ECS Inc. International"
			(at 342.43 -54.17 0)
			(layer "F.Fab")
			(hide yes)
			(effects
				(font
					(size 1 1)
					(thickness 0.15)
				)
			)
		)
		(property "Public" ""
			(at 342.43 -54.17 0)
			(layer "F.Fab")
			(hide yes)
			(effects
				(font
					(size 1 1)
					(thickness 0.15)
				)
			)
		)
		(property "Val" "50 MHz"
			(at 342.43 -54.17 0)
			(layer "F.Fab")
			(hide yes)
			(effects
				(font
					(size 1 1)
					(thickness 0.15)
				)
			)
		)
		(sheetname "/FPGA HSIO/")
		(sheetfile "fpga-hsio.kicad_sch")
		(attr smd)
		(fp_line
			(start 0.97 -1.17)
			(end 0.5 -1.17)
			(stroke
				(width 0.15)
				(type solid)
			)
			(layer "F.SilkS")
		)
		(fp_line
			(start -0.97 -1.17)
			(end -0.5 -1.17)
			(stroke
				(width 0.15)
				(type solid)
			)
			(layer "F.SilkS")
		)
		(fp_line
			(start 0.97 -0.7)
			(end 0.97 -1.17)
			(stroke
				(width 0.15)
				(type solid)
			)
			(layer "F.SilkS")
		)
		(fp_line
			(start -0.97 -0.7)
			(end -0.97 -1.17)
			(stroke
				(width 0.15)
				(type solid)
			)
			(layer "F.SilkS")
		)
		(fp_line
			(start 0.97 0.7)
			(end 0.97 1.17)
			(stroke
				(width 0.15)
				(type solid)
			)
			(layer "F.SilkS")
		)
		(fp_line
			(start -0.97 0.7)
			(end -0.97 1.17)
			(stroke
				(width 0.15)
				(type solid)
			)
			(layer "F.SilkS")
		)
		(fp_line
			(start 0.97 1.17)
			(end 0.5 1.17)
			(stroke
				(width 0.15)
				(type solid)
			)
			(layer "F.SilkS")
		)
		(fp_line
			(start -0.97 1.17)
			(end -0.5 1.17)
			(stroke
				(width 0.15)
				(type solid)
			)
			(layer "F.SilkS")
		)
		(fp_circle
			(center -1.05 -0.55)
			(end -1 -0.55)
			(stroke
				(width 0.15)
				(type solid)
			)
			(fill yes)
			(layer "F.SilkS")
		)
		(fp_rect
			(start -0.75 -0.95)
			(end 0.75 0.95)
			(stroke
				(width 0.05)
				(type solid)
			)
			(fill no)
			(layer "F.CrtYd")
		)
		(fp_line
			(start 0.6 -0.8)
			(end 0.6 0.8)
			(stroke
				(width 0.15)
				(type solid)
			)
			(layer "F.Fab")
		)
		(fp_line
			(start -0.6 -0.8)
			(end 0.6 -0.8)
			(stroke
				(width 0.15)
				(type solid)
			)
			(layer "F.Fab")
		)
		(fp_line
			(start 0.6 0.8)
			(end -0.6 0.8)
			(stroke
				(width 0.15)
				(type solid)
			)
			(layer "F.Fab")
		)
		(fp_line
			(start -0.6 0.8)
			(end -0.6 -0.8)
			(stroke
				(width 0.15)
				(type solid)
			)
			(layer "F.Fab")
		)
		(fp_text user "Author: Antmicro"
			(at 1.75 3.45 90)
			(layer "F.Fab")
			(effects
				(font
					(size 0.7 0.7)
					(thickness 0.15)
				)
				(justify left bottom)
			)
		)
		(fp_text user "License: Apache-2.0"
			(at 1.75 2.25 90)
			(layer "F.Fab")
			(effects
				(font
					(size 0.7 0.7)
					(thickness 0.15)
				)
				(justify left bottom)
			)
		)
		(fp_text user "${REFERENCE}"
			(at 1.75 4.65 90)
			(layer "F.Fab")
			(effects
				(font
					(size 0.7 0.7)
					(thickness 0.15)
				)
				(justify left bottom)
			)
		)
		(pad "1" smd rect
			(at -0.4 -0.55 90)
			(size 0.5 0.6)
			(layers "F.Cu" "F.Mask" "F.Paste")
			(net 48 "+1V8")
			(pinfunction "EN")
			(pintype "input")
			(solder_mask_margin 0.102)
		)
		(pad "2" smd rect
			(at -0.4 0.55 90)
			(size 0.5 0.6)
			(layers "F.Cu" "F.Mask" "F.Paste")
			(net 417 "GND")
			(pinfunction "GND")
			(pintype "power_in")
			(solder_mask_margin 0.102)
		)
		(pad "3" smd rect
			(at 0.4 0.55 90)
			(size 0.5 0.6)
			(layers "F.Cu" "F.Mask" "F.Paste")
			(net 336 "/FPGA HSIO/PF_CLK")
			(pinfunction "OUT")
			(pintype "output")
			(solder_mask_margin 0.102)
		)
		(pad "4" smd rect
			(at 0.4 -0.55 90)
			(size 0.5 0.6)
			(layers "F.Cu" "F.Mask" "F.Paste")
			(net 48 "+1V8")
			(pinfunction "VDD")
			(pintype "power_in")
			(solder_mask_margin 0.102)
		)
	)
)
